(kicad_pcb
	(version 20260206)
	(generator "pcbnew")
	(generator_version "10.0")
	(general
		(thickness 1.6)
		(legacy_teardrops no)
	)
	(paper "A4")
	(title_block
		(title "04192023_DAF0TMB3IC0_F0TG_MB_C_brd_V02_OCP.brd")
		(comment 1 "Grand Teton / footprint 3975 of 8354 (U6014), pads 224-336 of 354")
	)
	(layers
		(0 "F.Cu" signal "TOP")
		(4 "In1.Cu" signal "GND")
		(6 "In2.Cu" signal "IN1")
		(8 "In3.Cu" signal "GND1")
		(10 "In4.Cu" signal "IN2")
		(12 "In5.Cu" signal "GND2")
		(14 "In6.Cu" signal "IN3")
		(16 "In7.Cu" signal "GND3")
		(18 "In8.Cu" signal "VCC")
		(20 "In9.Cu" signal "VCC1")
		(22 "In10.Cu" signal "GND4")
		(24 "In11.Cu" signal "IN4")
		(26 "In12.Cu" signal "GND5")
		(28 "In13.Cu" signal "IN5")
		(30 "In14.Cu" signal "GND6")
		(32 "In15.Cu" signal "IN6")
		(34 "In16.Cu" signal "GND7")
		(2 "B.Cu" signal "BOTTOM")
		(9 "F.Adhes" user "F.Adhesive")
		(11 "B.Adhes" user "B.Adhesive")
		(13 "F.Paste" user "Package Geometry/Pastemask Top")
		(15 "B.Paste" user "Package Geometry/Pastemask Bottom")
		(5 "F.SilkS" user "Ref Des/Silkscreen Top")
		(7 "B.SilkS" user "Ref Des/Silkscreen Bottom")
		(1 "F.Mask" user "Board Geometry/Soldermask Top")
		(3 "B.Mask" user "Board Geometry/Soldermask Bottom")
		(17 "Dwgs.User" user "User.Drawings")
		(19 "Cmts.User" user "User.Comments")
		(21 "Eco1.User" user "User.Eco1")
		(23 "Eco2.User" user "User.Eco2")
		(25 "Edge.Cuts" user "Board Geometry/Outline")
		(27 "Margin" user)
		(31 "F.CrtYd" user "Package Geometry/Place Bound Top")
		(29 "B.CrtYd" user "Package Geometry/Place Bound Bottom")
		(35 "F.Fab" user "Ref Des/Assembly Top")
		(33 "B.Fab" user "Ref Des/Assembly Bottom")
	)
	(footprint ""
		(layer "F.Cu")
		(at 56.46801 -387.342634)
		(property "Reference" "U6014"
			(at -6.735064 -7.919974 0)
			(unlocked yes)
			(layer "F.SilkS")
			(effects
				(font
					(size 0.7874 0.5842)
					(thickness 0.1524)
				)
				(justify left)
			)
		)
		(property "Value" ""
			(at 0 0 0)
			(layer "F.Fab")
			(effects
				(font
					(size 1.27 1.27)
				)
			)
		)
		(duplicate_pad_numbers_are_jumpers no)
		(pad "DY32" smd circle
			(at -5.997448 2.724912)
			(size 0.381 0.381)
			(layers "F.Cu" "F.Mask" "F.Paste")
			(net "GND")
		)
		(pad "E8" smd circle
			(at 10.366502 -1.988312)
			(size 0.3048 0.3048)
			(layers "F.Cu" "F.Mask" "F.Paste")
			(net "JTAG_TRST_RT_CPU1_P0_N")
		)
		(pad "E11" smd circle
			(at 10.366502 -1.388364)
			(size 0.3048 0.3048)
			(layers "F.Cu" "F.Mask" "F.Paste")
			(net "RXDET_BYP_RT_CPU1_P0")
		)
		(pad "E14" smd circle
			(at 10.366502 -0.788416)
			(size 0.3048 0.3048)
			(layers "F.Cu" "F.Mask" "F.Paste")
			(net "GND")
		)
		(pad "E18" smd circle
			(at 10.366502 -0.188468)
			(size 0.3048 0.3048)
			(layers "F.Cu" "F.Mask" "F.Paste")
			(net "Net_2216")
		)
		(pad "E27" smd circle
			(at 10.366502 1.61163)
			(size 0.3048 0.3048)
			(layers "F.Cu" "F.Mask" "F.Paste")
			(net "GND")
		)
		(pad "E30" smd circle
			(at 10.366502 2.211578)
			(size 0.3048 0.3048)
			(layers "F.Cu" "F.Mask" "F.Paste")
			(net "GND")
		)
		(pad "E33" smd circle
			(at 10.366502 2.811526)
			(size 0.3048 0.3048)
			(layers "F.Cu" "F.Mask" "F.Paste")
			(net "GND")
		)
		(pad "EA2" smd circle
			(at -6.050026 -3.41884)
			(size 0.3048 0.3048)
			(layers "F.Cu" "F.Mask" "F.Paste")
			(net "GND")
		)
		(pad "EA34" smd circle
			(at -6.050026 3.420364)
			(size 0.3048 0.3048)
			(layers "F.Cu" "F.Mask" "F.Paste")
			(net "GND")
		)
		(pad "EB1" smd oval
			(at -6.35 -3.938524)
			(size 0.254 0.3302)
			(layers "F.Cu" "F.Mask" "F.Paste")
			(net "GND")
		)
		(pad "EB35" smd oval
			(at -6.35 3.940048)
			(size 0.254 0.3302)
			(layers "F.Cu" "F.Mask" "F.Paste")
			(net "GND")
		)
		(pad "EC7" smd circle
			(at -6.397498 -2.12471)
			(size 0.381 0.381)
			(layers "F.Cu" "F.Mask" "F.Paste")
			(net "P5E_CPU1_P0_TX_BUF_DP<2>")
		)
		(pad "EC26" smd circle
			(at -6.397498 1.339342)
			(size 0.381 0.381)
			(layers "F.Cu" "F.Mask" "F.Paste")
			(net "P5E_CPU1_P0_RX_DP<2>")
		)
		(pad "ED2" smd circle
			(at -6.649974 -3.41884)
			(size 0.3048 0.3048)
			(layers "F.Cu" "F.Mask" "F.Paste")
			(net "P5E_CPU1_P0_RX_BUF_DN<2>")
		)
		(pad "ED34" smd circle
			(at -6.649974 3.420364)
			(size 0.3048 0.3048)
			(layers "F.Cu" "F.Mask" "F.Paste")
			(net "P5E_CPU1_P0_TX_C_DN<2>")
		)
		(pad "EE10" smd circle
			(at -6.797294 -1.431798)
			(size 0.381 0.381)
			(layers "F.Cu" "F.Mask" "F.Paste")
			(net "P5E_CPU1_P0_TX_BUF_DN<2>")
		)
		(pad "EE29" smd circle
			(at -6.797294 2.032254)
			(size 0.381 0.381)
			(layers "F.Cu" "F.Mask" "F.Paste")
			(net "P5E_CPU1_P0_RX_DN<2>")
		)
		(pad "EF1" smd oval
			(at -6.949948 -3.938524)
			(size 0.254 0.3302)
			(layers "F.Cu" "F.Mask" "F.Paste")
			(net "P5E_CPU1_P0_RX_BUF_DP<2>")
		)
		(pad "EF35" smd oval
			(at -6.949948 3.940048)
			(size 0.254 0.3302)
			(layers "F.Cu" "F.Mask" "F.Paste")
			(net "P5E_CPU1_P0_TX_C_DP<2>")
		)
		(pad "EG4" smd circle
			(at -7.197344 -2.817368)
			(size 0.381 0.381)
			(layers "F.Cu" "F.Mask" "F.Paste")
			(net "GND")
		)
		(pad "EG13" smd circle
			(at -7.197344 -0.79629)
			(size 0.3048 0.3048)
			(layers "F.Cu" "F.Mask" "F.Paste")
			(net "GND")
		)
		(pad "EG17" smd circle
			(at -7.197344 -0.296164)
			(size 0.3048 0.3048)
			(layers "F.Cu" "F.Mask" "F.Paste")
			(net "P0V9_CPU1_RT0_2A")
		)
		(pad "EG20" smd circle
			(at -7.197344 0.203708)
			(size 0.3048 0.3048)
			(layers "F.Cu" "F.Mask" "F.Paste")
			(net "P0V9_CPU1_RT0_2A")
		)
		(pad "EG22" smd circle
			(at -7.197344 0.703834)
			(size 0.3048 0.3048)
			(layers "F.Cu" "F.Mask" "F.Paste")
			(net "GND")
		)
		(pad "EG32" smd circle
			(at -7.197344 2.724912)
			(size 0.381 0.381)
			(layers "F.Cu" "F.Mask" "F.Paste")
			(net "GND")
		)
		(pad "EH2" smd circle
			(at -7.249922 -3.41884)
			(size 0.3048 0.3048)
			(layers "F.Cu" "F.Mask" "F.Paste")
			(net "GND")
		)
		(pad "EH34" smd circle
			(at -7.249922 3.420364)
			(size 0.3048 0.3048)
			(layers "F.Cu" "F.Mask" "F.Paste")
			(net "GND")
		)
		(pad "EJ1" smd oval
			(at -7.549896 -3.938524)
			(size 0.254 0.3302)
			(layers "F.Cu" "F.Mask" "F.Paste")
			(net "GND")
		)
		(pad "EJ35" smd oval
			(at -7.549896 3.940048)
			(size 0.254 0.3302)
			(layers "F.Cu" "F.Mask" "F.Paste")
			(net "GND")
		)
		(pad "EK7" smd circle
			(at -7.597394 -2.12471)
			(size 0.381 0.381)
			(layers "F.Cu" "F.Mask" "F.Paste")
			(net "P5E_CPU1_P0_TX_BUF_DP<1>")
		)
		(pad "EK26" smd circle
			(at -7.597394 1.339342)
			(size 0.381 0.381)
			(layers "F.Cu" "F.Mask" "F.Paste")
			(net "P5E_CPU1_P0_RX_DP<1>")
		)
		(pad "EL2" smd circle
			(at -7.850124 -3.41884)
			(size 0.3048 0.3048)
			(layers "F.Cu" "F.Mask" "F.Paste")
			(net "P5E_CPU1_P0_RX_BUF_DN<1>")
		)
		(pad "EL34" smd circle
			(at -7.850124 3.420364)
			(size 0.3048 0.3048)
			(layers "F.Cu" "F.Mask" "F.Paste")
			(net "P5E_CPU1_P0_TX_C_DP<1>")
		)
		(pad "EM10" smd circle
			(at -7.997444 -1.431798)
			(size 0.381 0.381)
			(layers "F.Cu" "F.Mask" "F.Paste")
			(net "P5E_CPU1_P0_TX_BUF_DN<1>")
		)
		(pad "EM29" smd circle
			(at -7.997444 2.032254)
			(size 0.381 0.381)
			(layers "F.Cu" "F.Mask" "F.Paste")
			(net "P5E_CPU1_P0_RX_DN<1>")
		)
		(pad "EN1" smd oval
			(at -8.150098 -3.938524)
			(size 0.254 0.3302)
			(layers "F.Cu" "F.Mask" "F.Paste")
			(net "P5E_CPU1_P0_RX_BUF_DP<1>")
		)
		(pad "EN35" smd oval
			(at -8.150098 3.940048)
			(size 0.254 0.3302)
			(layers "F.Cu" "F.Mask" "F.Paste")
			(net "P5E_CPU1_P0_TX_C_DN<1>")
		)
		(pad "EP4" smd circle
			(at -8.397494 -2.817368)
			(size 0.381 0.381)
			(layers "F.Cu" "F.Mask" "F.Paste")
			(net "GND")
		)
		(pad "EP13" smd circle
			(at -8.397494 -0.79629)
			(size 0.3048 0.3048)
			(layers "F.Cu" "F.Mask" "F.Paste")
			(net "GND")
		)
		(pad "EP17" smd circle
			(at -8.397494 -0.296164)
			(size 0.3048 0.3048)
			(layers "F.Cu" "F.Mask" "F.Paste")
			(net "P0V9_CPU1_RT0_2A")
		)
		(pad "EP20" smd circle
			(at -8.397494 0.203708)
			(size 0.3048 0.3048)
			(layers "F.Cu" "F.Mask" "F.Paste")
			(net "P0V9_CPU1_RT0_2A")
		)
		(pad "EP22" smd circle
			(at -8.397494 0.703834)
			(size 0.3048 0.3048)
			(layers "F.Cu" "F.Mask" "F.Paste")
			(net "GND")
		)
		(pad "EP32" smd circle
			(at -8.397494 2.724912)
			(size 0.381 0.381)
			(layers "F.Cu" "F.Mask" "F.Paste")
			(net "GND")
		)
		(pad "ER2" smd circle
			(at -8.450072 -3.41884)
			(size 0.3048 0.3048)
			(layers "F.Cu" "F.Mask" "F.Paste")
			(net "GND")
		)
		(pad "ER34" smd circle
			(at -8.450072 3.420364)
			(size 0.3048 0.3048)
			(layers "F.Cu" "F.Mask" "F.Paste")
			(net "GND")
		)
		(pad "ET1" smd oval
			(at -8.750046 -3.938524)
			(size 0.254 0.3302)
			(layers "F.Cu" "F.Mask" "F.Paste")
			(net "GND")
		)
		(pad "ET35" smd oval
			(at -8.750046 3.940048)
			(size 0.254 0.3302)
			(layers "F.Cu" "F.Mask" "F.Paste")
			(net "GND")
		)
		(pad "EU7" smd circle
			(at -8.79729 -2.12471)
			(size 0.381 0.381)
			(layers "F.Cu" "F.Mask" "F.Paste")
			(net "P5E_CPU1_P0_TX_BUF_DP<0>")
		)
		(pad "EU26" smd circle
			(at -8.79729 1.339342)
			(size 0.381 0.381)
			(layers "F.Cu" "F.Mask" "F.Paste")
			(net "P5E_CPU1_P0_RX_DP<0>")
		)
		(pad "EV2" smd circle
			(at -9.05002 -3.41884)
			(size 0.3048 0.3048)
			(layers "F.Cu" "F.Mask" "F.Paste")
			(net "P5E_CPU1_P0_RX_BUF_DN<0>")
		)
		(pad "EV34" smd circle
			(at -9.05002 3.420364)
			(size 0.3048 0.3048)
			(layers "F.Cu" "F.Mask" "F.Paste")
			(net "P5E_CPU1_P0_TX_C_DN<0>")
		)
		(pad "EW10" smd circle
			(at -9.19734 -1.431798)
			(size 0.381 0.381)
			(layers "F.Cu" "F.Mask" "F.Paste")
			(net "P5E_CPU1_P0_TX_BUF_DN<0>")
		)
		(pad "EW29" smd circle
			(at -9.19734 2.032254)
			(size 0.381 0.381)
			(layers "F.Cu" "F.Mask" "F.Paste")
			(net "P5E_CPU1_P0_RX_DN<0>")
		)
		(pad "EY1" smd oval
			(at -9.349994 -3.938524)
			(size 0.254 0.3302)
			(layers "F.Cu" "F.Mask" "F.Paste")
			(net "P5E_CPU1_P0_RX_BUF_DP<0>")
		)
		(pad "EY35" smd oval
			(at -9.349994 3.940048)
			(size 0.254 0.3302)
			(layers "F.Cu" "F.Mask" "F.Paste")
			(net "P5E_CPU1_P0_TX_C_DP<0>")
		)
		(pad "F2" smd circle
			(at 10.150094 -3.41884)
			(size 0.3048 0.3048)
			(layers "F.Cu" "F.Mask" "F.Paste")
			(net "RST_RT_CPU1_P0_PERST_N")
		)
		(pad "F34" smd circle
			(at 10.150094 3.420364)
			(size 0.3048 0.3048)
			(layers "F.Cu" "F.Mask" "F.Paste")
			(net "RT_CPU1_P0_ADDR1")
		)
		(pad "FA15" smd circle
			(at -9.59739 -0.738886)
			(size 0.381 0.381)
			(layers "F.Cu" "F.Mask" "F.Paste")
			(net "GND")
		)
		(pad "FA32" smd circle
			(at -9.59739 2.724912)
			(size 0.381 0.381)
			(layers "F.Cu" "F.Mask" "F.Paste")
			(net "GND")
		)
		(pad "FB2" smd circle
			(at -9.649968 -3.41884)
			(size 0.3048 0.3048)
			(layers "F.Cu" "F.Mask" "F.Paste")
			(net "GND")
		)
		(pad "FB34" smd circle
			(at -9.649968 3.420364)
			(size 0.3048 0.3048)
			(layers "F.Cu" "F.Mask" "F.Paste")
			(net "GND")
		)
		(pad "FC3" smd circle
			(at -9.846818 -2.888488)
			(size 0.3048 0.3048)
			(layers "F.Cu" "F.Mask" "F.Paste")
			(net "GND")
		)
		(pad "FC6" smd circle
			(at -9.846818 -2.288286)
			(size 0.3048 0.3048)
			(layers "F.Cu" "F.Mask" "F.Paste")
			(net "GND")
		)
		(pad "FC9" smd circle
			(at -9.846818 -1.688338)
			(size 0.3048 0.3048)
			(layers "F.Cu" "F.Mask" "F.Paste")
			(net "GND")
		)
		(pad "FC19" smd circle
			(at -9.846818 0.111506)
			(size 0.3048 0.3048)
			(layers "F.Cu" "F.Mask" "F.Paste")
			(net "GND")
		)
		(pad "FC23" smd circle
			(at -9.846818 0.711708)
			(size 0.3048 0.3048)
			(layers "F.Cu" "F.Mask" "F.Paste")
			(net "GND")
		)
		(pad "FC25" smd circle
			(at -9.846818 1.311656)
			(size 0.3048 0.3048)
			(layers "F.Cu" "F.Mask" "F.Paste")
			(net "GND")
		)
		(pad "FC28" smd circle
			(at -9.846818 1.911604)
			(size 0.3048 0.3048)
			(layers "F.Cu" "F.Mask" "F.Paste")
			(net "GND")
		)
		(pad "FD1" smd oval
			(at -9.949942 -3.938524)
			(size 0.254 0.3302)
			(layers "F.Cu" "F.Mask" "F.Paste")
			(net "GND")
		)
		(pad "FD35" smd oval
			(at -9.949942 3.940048)
			(size 0.254 0.3302)
			(layers "F.Cu" "F.Mask" "F.Paste")
			(net "GND")
		)
		(pad "FE2" smd circle
			(at -10.249916 -3.41884)
			(size 0.3048 0.3048)
			(layers "F.Cu" "F.Mask" "F.Paste")
			(net "NCF_CPU1_P0_GND")
		)
		(pad "FE34" smd circle
			(at -10.249916 3.420364)
			(size 0.3048 0.3048)
			(layers "F.Cu" "F.Mask" "F.Paste")
			(net "NCF_CPU1_P0_GND")
		)
		(pad "FF5" smd circle
			(at -10.366248 -2.588514)
			(size 0.3048 0.3048)
			(layers "F.Cu" "F.Mask" "F.Paste")
			(net "SMB_RT_CPU1_P0_ROM_MUX_1D_R_SCL")
		)
		(pad "FF8" smd circle
			(at -10.366248 -1.988312)
			(size 0.3048 0.3048)
			(layers "F.Cu" "F.Mask" "F.Paste")
			(net "JTAG_TEST_MODE_RT_CPU1_P0")
		)
		(pad "FF11" smd circle
			(at -10.366248 -1.388364)
			(size 0.3048 0.3048)
			(layers "F.Cu" "F.Mask" "F.Paste")
			(net "RST_RT_CPU1_P0_RESET_N")
		)
		(pad "FF14" smd circle
			(at -10.366248 -0.788416)
			(size 0.3048 0.3048)
			(layers "F.Cu" "F.Mask" "F.Paste")
			(net "GND")
		)
		(pad "FF18" smd circle
			(at -10.366248 -0.188468)
			(size 0.3048 0.3048)
			(layers "F.Cu" "F.Mask" "F.Paste")
			(net "CLK_100M_RETIMER_CPU1_P0_DN")
		)
		(pad "FF21" smd circle
			(at -10.366248 0.41148)
			(size 0.3048 0.3048)
			(layers "F.Cu" "F.Mask" "F.Paste")
			(net "GND")
		)
		(pad "FF24" smd circle
			(at -10.366248 1.011682)
			(size 0.3048 0.3048)
			(layers "F.Cu" "F.Mask" "F.Paste")
			(net "TEST0_RT_CPU1_P0")
		)
		(pad "FF27" smd circle
			(at -10.366248 1.61163)
			(size 0.3048 0.3048)
			(layers "F.Cu" "F.Mask" "F.Paste")
			(net "TEST1_RT_CPU1_P0")
		)
		(pad "FF30" smd circle
			(at -10.366248 2.211578)
			(size 0.3048 0.3048)
			(layers "F.Cu" "F.Mask" "F.Paste")
			(net "TEST2_RT_CPU1_P0")
		)
		(pad "FF33" smd circle
			(at -10.366248 2.811526)
			(size 0.3048 0.3048)
			(layers "F.Cu" "F.Mask" "F.Paste")
			(net "RT_CPU1_P0_SCAN_MODE")
		)
		(pad "FG1" smd oval
			(at -10.54989 -3.938524)
			(size 0.254 0.3302)
			(layers "F.Cu" "F.Mask" "F.Paste")
			(net "NCF_CPU1_P0_GND")
		)
		(pad "FG35" smd oval
			(at -10.54989 3.940048)
			(size 0.254 0.3302)
			(layers "F.Cu" "F.Mask" "F.Paste")
			(net "NCF_CPU1_P0_GND")
		)
		(pad "FH2" smd circle
			(at -10.850118 -3.41884)
			(size 0.3048 0.3048)
			(layers "F.Cu" "F.Mask" "F.Paste")
			(net "NCF_CPU1_P0_GND")
		)
		(pad "FH34" smd circle
			(at -10.850118 3.420364)
			(size 0.3048 0.3048)
			(layers "F.Cu" "F.Mask" "F.Paste")
			(net "NCF_CPU1_P0_GND")
		)
		(pad "FJ3" smd oval
			(at -10.885932 -2.888488 90)
			(size 0.254 0.3302)
			(layers "F.Cu" "F.Mask" "F.Paste")
			(net "SMB_RT_CPU1_P0_ROM_MUX_1D_R_SDA")
		)
		(pad "FJ6" smd oval
			(at -10.885932 -2.288286 90)
			(size 0.254 0.3302)
			(layers "F.Cu" "F.Mask" "F.Paste")
			(net "Net_561")
		)
		(pad "FJ9" smd oval
			(at -10.885932 -1.688338 90)
			(size 0.254 0.3302)
			(layers "F.Cu" "F.Mask" "F.Paste")
			(net "MODE_RT_CPU1_P0")
		)
		(pad "FJ12" smd oval
			(at -10.885932 -1.08839 90)
			(size 0.254 0.3302)
			(layers "F.Cu" "F.Mask" "F.Paste")
			(net "GND")
		)
		(pad "FJ16" smd oval
			(at -10.885932 -0.488442 90)
			(size 0.254 0.3302)
			(layers "F.Cu" "F.Mask" "F.Paste")
			(net "CLK_100M_RETIMER_CPU1_P0_DP")
		)
		(pad "FJ19" smd oval
			(at -10.885932 0.111506 90)
			(size 0.254 0.3302)
			(layers "F.Cu" "F.Mask" "F.Paste")
			(net "GND")
		)
		(pad "FJ23" smd oval
			(at -10.885932 0.711708 90)
			(size 0.254 0.3302)
			(layers "F.Cu" "F.Mask" "F.Paste")
			(net "Net_562")
		)
		(pad "FJ25" smd oval
			(at -10.885932 1.311656 90)
			(size 0.254 0.3302)
			(layers "F.Cu" "F.Mask" "F.Paste")
			(net "GPIO2_RT_CPU1_P0")
		)
		(pad "FJ28" smd oval
			(at -10.885932 1.911604 90)
			(size 0.254 0.3302)
			(layers "F.Cu" "F.Mask" "F.Paste")
			(net "GPIO3_RT_CPU1_P0")
		)
		(pad "FJ31" smd oval
			(at -10.885932 2.511552 90)
			(size 0.254 0.3302)
			(layers "F.Cu" "F.Mask" "F.Paste")
			(net "Net_54")
		)
		(pad "G1" smd oval
			(at 9.85012 -3.938524)
			(size 0.254 0.3302)
			(layers "F.Cu" "F.Mask" "F.Paste")
			(net "RT_CPU1_P0_VQPS")
		)
		(pad "G35" smd oval
			(at 9.85012 3.940048)
			(size 0.254 0.3302)
			(layers "F.Cu" "F.Mask" "F.Paste")
			(net "CLKREQ_RT_CPU1_P0_N")
		)
		(pad "H12" smd circle
			(at 9.846818 -1.08839)
			(size 0.3048 0.3048)
			(layers "F.Cu" "F.Mask" "F.Paste")
			(net "GND")
		)
		(pad "H16" smd circle
			(at 9.846818 -0.488442)
			(size 0.3048 0.3048)
			(layers "F.Cu" "F.Mask" "F.Paste")
			(net "GND")
		)
		(pad "H19" smd circle
			(at 9.846818 0.111506)
			(size 0.3048 0.3048)
			(layers "F.Cu" "F.Mask" "F.Paste")
			(net "GND")
		)
		(pad "H31" smd circle
			(at 9.846818 2.511552)
			(size 0.3048 0.3048)
			(layers "F.Cu" "F.Mask" "F.Paste")
			(net "GND")
		)
		(pad "J4" smd circle
			(at 9.602724 -2.817368)
			(size 0.381 0.381)
			(layers "F.Cu" "F.Mask" "F.Paste")
			(net "GND")
		)
		(pad "J22" smd circle
			(at 9.602724 0.703834)
			(size 0.3048 0.3048)
			(layers "F.Cu" "F.Mask" "F.Paste")
			(net "GND")
		)
		(pad "K2" smd circle
			(at 9.549892 -3.41884)
			(size 0.3048 0.3048)
			(layers "F.Cu" "F.Mask" "F.Paste")
			(net "GND")
		)
		(pad "K34" smd circle
			(at 9.549892 3.420364)
			(size 0.3048 0.3048)
			(layers "F.Cu" "F.Mask" "F.Paste")
			(net "GND")
		)
		(pad "L1" smd oval
			(at 9.249918 -3.938524)
			(size 0.254 0.3302)
			(layers "F.Cu" "F.Mask" "F.Paste")
			(net "GND")
		)
		(pad "L35" smd oval
			(at 9.249918 3.940048)
			(size 0.254 0.3302)
			(layers "F.Cu" "F.Mask" "F.Paste")
			(net "GND")
		)
		(pad "M7" smd circle
			(at 9.202674 -2.12471)
			(size 0.381 0.381)
			(layers "F.Cu" "F.Mask" "F.Paste")
			(net "P5E_CPU1_P0_TX_BUF_DP<15>")
		)
		(pad "M26" smd circle
			(at 9.202674 1.339342)
			(size 0.381 0.381)
			(layers "F.Cu" "F.Mask" "F.Paste")
			(net "P5E_CPU1_P0_RX_DP<15>")
		)
		(pad "N2" smd circle
			(at 8.949944 -3.41884)
			(size 0.3048 0.3048)
			(layers "F.Cu" "F.Mask" "F.Paste")
			(net "P5E_CPU1_P0_RX_BUF_DN<15>")
		)
		(pad "N34" smd circle
			(at 8.949944 3.420364)
			(size 0.3048 0.3048)
			(layers "F.Cu" "F.Mask" "F.Paste")
			(net "P5E_CPU1_P0_TX_C_DN<15>")
		)
	)
)
